# discovery-power-board-v1-revB — discovery.sch (kicad5-legacy-schematic(.sch))
EESchema Schematic File Version 4
LIBS:discovery-cache
EELAYER 26 0
EELAYER END
$Descr A4 11693 8268
encoding utf-8
Sheet 1 1
Title ""
Date ""
Rev ""
Comp ""
Comment1 ""
Comment2 ""
Comment3 ""
Comment4 ""
$EndDescr
$Comp
L Connector_Generic:Conn_02x04_Counter_Clockwise J1
U 1 1 5C48C101
P 1900 2250
F 0 "J1" H 1950 2450 50  0000 C CNN
F 1 "Conn_02x04_CPU" H 2050 1950 50  0000 C CNN
F 2 "discovery:CONN_02x04_4.2mm" H 1900 2250 50  0001 C CNN
F 3 "~" H 1900 2250 50  0001 C CNN
	1    1900 2250
	1    0    0    -1  
$EndComp
Wire Wire Line
	1700 2150 1600 2150
Wire Wire Line
	1700 2250 1600 2250
Wire Wire Line
	1600 2250 1600 2150
Wire Wire Line
	1700 2350 1600 2350
Wire Wire Line
	1600 2350 1600 2250
Connection ~ 1600 2250
Wire Wire Line
	1700 2450 1600 2450
Wire Wire Line
	1600 2450 1600 2350
Connection ~ 1600 2350
Wire Wire Line
	2200 2150 2300 2150
Wire Wire Line
	2300 2150 2300 2250
Wire Wire Line
	2200 2450 2300 2450
Wire Wire Line
	2200 2350 2300 2350
Connection ~ 2300 2350
Wire Wire Line
	2300 2350 2300 2450
Wire Wire Line
	2200 2250 2300 2250
Connection ~ 2300 2250
Wire Wire Line
	2300 2250 2300 2350
$Comp
L power:+12V #PWR01
U 1 1 5C48C5D0
P 2300 2050
F 0 "#PWR01" H 2300 1900 50  0001 C CNN
F 1 "+12V" H 2315 2223 50  0000 C CNN
F 2 "" H 2300 2050 50  0001 C CNN
F 3 "" H 2300 2050 50  0001 C CNN
	1    2300 2050
	1    0    0    -1  
$EndComp
$Comp
L power:GND #PWR03
U 1 1 5C48C659
P 1600 2550
F 0 "#PWR03" H 1600 2300 50  0001 C CNN
F 1 "GND" H 1605 2377 50  0000 C CNN
F 2 "" H 1600 2550 50  0001 C CNN
F 3 "" H 1600 2550 50  0001 C CNN
	1    1600 2550
	1    0    0    -1  
$EndComp
$Comp
L Connector_Generic:Conn_02x04_Counter_Clockwise J3
U 1 1 5C48C722
P 2950 2250
F 0 "J3" H 3000 2450 50  0000 C CNN
F 1 "Conn_02x04_CPU" H 3100 1950 50  0000 C CNN
F 2 "discovery:CONN_02x04_4.2mm" H 2950 2250 50  0001 C CNN
F 3 "~" H 2950 2250 50  0001 C CNN
	1    2950 2250
	1    0    0    -1  
$EndComp
Wire Wire Line
	2750 2150 2650 2150
Wire Wire Line
	2750 2250 2650 2250
Wire Wire Line
	2650 2250 2650 2150
Wire Wire Line
	2750 2350 2650 2350
Wire Wire Line
	2650 2350 2650 2250
Connection ~ 2650 2250
Wire Wire Line
	2750 2450 2650 2450
Wire Wire Line
	2650 2450 2650 2350
Connection ~ 2650 2350
Wire Wire Line
	3250 2150 3350 2150
Wire Wire Line
	3350 2150 3350 2250
Wire Wire Line
	3250 2450 3350 2450
Wire Wire Line
	3250 2350 3350 2350
Connection ~ 3350 2350
Wire Wire Line
	3350 2350 3350 2450
Wire Wire Line
	3250 2250 3350 2250
Connection ~ 3350 2250
Wire Wire Line
	3350 2250 3350 2350
$Comp
L power:+12V #PWR05
U 1 1 5C48C73E
P 3350 2050
F 0 "#PWR05" H 3350 1900 50  0001 C CNN
F 1 "+12V" H 3365 2223 50  0000 C CNN
F 2 "" H 3350 2050 50  0001 C CNN
F 3 "" H 3350 2050 50  0001 C CNN
	1    3350 2050
	1    0    0    -1  
$EndComp
$Comp
L power:GND #PWR07
U 1 1 5C48C744
P 2650 2550
F 0 "#PWR07" H 2650 2300 50  0001 C CNN
F 1 "GND" H 2655 2377 50  0000 C CNN
F 2 "" H 2650 2550 50  0001 C CNN
F 3 "" H 2650 2550 50  0001 C CNN
	1    2650 2550
	1    0    0    -1  
$EndComp
$Comp
L power:+12V #PWR013
U 1 1 5C4ED06B
P 5650 1100
F 0 "#PWR013" H 5650 950 50  0001 C CNN
F 1 "+12V" H 5665 1273 50  0000 C CNN
F 2 "" H 5650 1100 50  0001 C CNN
F 3 "" H 5650 1100 50  0001 C CNN
	1    5650 1100
	1    0    0    -1  
$EndComp
$Comp
L power:GND #PWR014
U 1 1 5C4ED1EC
P 6000 1100
F 0 "#PWR014" H 6000 850 50  0001 C CNN
F 1 "GND" H 6005 927 50  0000 C CNN
F 2 "" H 6000 1100 50  0001 C CNN
F 3 "" H 6000 1100 50  0001 C CNN
	1    6000 1100
	-1   0    0    1   
$EndComp
$Comp
L power:PWR_FLAG #FLG01
U 1 1 5C4ED4D6
P 5650 1250
F 0 "#FLG01" H 5650 1325 50  0001 C CNN
F 1 "PWR_FLAG" H 5650 1423 50  0000 C CNN
F 2 "" H 5650 1250 50  0001 C CNN
F 3 "~" H 5650 1250 50  0001 C CNN
	1    5650 1250
	-1   0    0    1   
$EndComp
$Comp
L power:PWR_FLAG #FLG02
U 1 1 5C4ED5C4
P 6000 1250
F 0 "#FLG02" H 6000 1325 50  0001 C CNN
F 1 "PWR_FLAG" H 6000 1423 50  0000 C CNN
F 2 "" H 6000 1250 50  0001 C CNN
F 3 "~" H 6000 1250 50  0001 C CNN
	1    6000 1250
	-1   0    0    1   
$EndComp
Wire Wire Line
	5650 1100 5650 1250
Wire Wire Line
	6000 1100 6000 1250
$Comp
L Connector:TestPoint W1
U 1 1 5C4F6750
P 6550 1150
F 0 "W1" H 6608 1270 50  0000 L CNN
F 1 "Fixing hole" V 6450 1000 50  0000 L CNN
F 2 "discovery:FixingPoint_Plated_Hole_D4.0mm" H 6750 1150 50  0001 C CNN
F 3 "~" H 6750 1150 50  0001 C CNN
	1    6550 1150
	1    0    0    -1  
$EndComp
$Comp
L power:GND #PWR015
U 1 1 5C4F7016
P 6550 1300
F 0 "#PWR015" H 6550 1050 50  0001 C CNN
F 1 "GND" H 6555 1127 50  0000 C CNN
F 2 "" H 6550 1300 50  0001 C CNN
F 3 "" H 6550 1300 50  0001 C CNN
	1    6550 1300
	1    0    0    -1  
$EndComp
Wire Wire Line
	6550 1300 6550 1150
$Comp
L Connector:TestPoint W2
U 1 1 5C4FA49E
P 6900 1150
F 0 "W2" H 6958 1270 50  0000 L CNN
F 1 "Fixing hole" V 6800 1000 50  0000 L CNN
F 2 "discovery:FixingPoint_Plated_Hole_D4.0mm" H 7100 1150 50  0001 C CNN
F 3 "~" H 7100 1150 50  0001 C CNN
	1    6900 1150
	1    0    0    -1  
$EndComp
$Comp
L power:GND #PWR016
U 1 1 5C4FA4A4
P 6900 1300
F 0 "#PWR016" H 6900 1050 50  0001 C CNN
F 1 "GND" H 6905 1127 50  0000 C CNN
F 2 "" H 6900 1300 50  0001 C CNN
F 3 "" H 6900 1300 50  0001 C CNN
	1    6900 1300
	1    0    0    -1  
$EndComp
Wire Wire Line
	6900 1300 6900 1150
$Comp
L Connector:TestPoint W3
U 1 1 5C4FD7CA
P 7250 1150
F 0 "W3" H 7308 1270 50  0000 L CNN
F 1 "Fixing hole" V 7150 1000 50  0000 L CNN
F 2 "discovery:FixingPoint_Plated_Hole_D4.0mm" H 7450 1150 50  0001 C CNN
F 3 "~" H 7450 1150 50  0001 C CNN
	1    7250 1150
	1    0    0    -1  
$EndComp
$Comp
L power:GND #PWR019
U 1 1 5C4FD7D0
P 7250 1300
F 0 "#PWR019" H 7250 1050 50  0001 C CNN
F 1 "GND" H 7255 1127 50  0000 C CNN
F 2 "" H 7250 1300 50  0001 C CNN
F 3 "" H 7250 1300 50  0001 C CNN
	1    7250 1300
	1    0    0    -1  
$EndComp
Wire Wire Line
	7250 1300 7250 1150
$Comp
L Connector:TestPoint W4
U 1 1 5C4FD7D7
P 7600 1150
F 0 "W4" H 7658 1270 50  0000 L CNN
F 1 "Fixing hole" V 7500 1000 50  0000 L CNN
F 2 "discovery:FixingPoint_Plated_Hole_D4.0mm" H 7800 1150 50  0001 C CNN
F 3 "~" H 7800 1150 50  0001 C CNN
	1    7600 1150
	1    0    0    -1  
$EndComp
$Comp
L power:GND #PWR020
U 1 1 5C4FD7DD
P 7600 1300
F 0 "#PWR020" H 7600 1050 50  0001 C CNN
F 1 "GND" H 7605 1127 50  0000 C CNN
F 2 "" H 7600 1300 50  0001 C CNN
F 3 "" H 7600 1300 50  0001 C CNN
	1    7600 1300
	1    0    0    -1  
$EndComp
Wire Wire Line
	7600 1300 7600 1150
$Comp
L Connector:TestPoint W5
U 1 1 5C7065CC
P 7150 2600
F 0 "W5" H 7208 2720 50  0000 L CNN
F 1 "Cable hole" V 7050 2450 50  0000 L CNN
F 2 "discovery:fixing_hole" H 7350 2600 50  0001 C CNN
F 3 "~" H 7350 2600 50  0001 C CNN
	1    7150 2600
	1    0    0    -1  
$EndComp
$Comp
L Connector:TestPoint W6
U 1 1 5C706602
P 7450 2600
F 0 "W6" H 7508 2720 50  0000 L CNN
F 1 "Cable hole" V 7350 2450 50  0000 L CNN
F 2 "discovery:fixing_hole" H 7650 2600 50  0001 C CNN
F 3 "~" H 7650 2600 50  0001 C CNN
	1    7450 2600
	1    0    0    -1  
$EndComp
$Comp
L Connector:TestPoint W7
U 1 1 5C70664A
P 7750 2600
F 0 "W7" H 7808 2720 50  0000 L CNN
F 1 "Cable hole" V 7650 2450 50  0000 L CNN
F 2 "discovery:fixing_hole" H 7950 2600 50  0001 C CNN
F 3 "~" H 7950 2600 50  0001 C CNN
	1    7750 2600
	1    0    0    -1  
$EndComp
$Comp
L Connector:TestPoint W12
U 1 1 5C706696
P 9250 2600
F 0 "W12" H 9308 2720 50  0000 L CNN
F 1 "Cable hole" V 9150 2450 50  0000 L CNN
F 2 "discovery:fixing_hole" H 9450 2600 50  0001 C CNN
F 3 "~" H 9450 2600 50  0001 C CNN
	1    9250 2600
	1    0    0    -1  
$EndComp
$Comp
L power:+12V #PWR017
U 1 1 5C7066E0
P 7150 2750
F 0 "#PWR017" H 7150 2600 50  0001 C CNN
F 1 "+12V" H 7165 2923 50  0000 C CNN
F 2 "" H 7150 2750 50  0001 C CNN
F 3 "" H 7150 2750 50  0001 C CNN
	1    7150 2750
	-1   0    0    1   
$EndComp
$Comp
L power:+12V #PWR018
U 1 1 5C70673F
P 7450 2750
F 0 "#PWR018" H 7450 2600 50  0001 C CNN
F 1 "+12V" H 7465 2923 50  0000 C CNN
F 2 "" H 7450 2750 50  0001 C CNN
F 3 "" H 7450 2750 50  0001 C CNN
	1    7450 2750
	-1   0    0    1   
$EndComp
$Comp
L power:+12V #PWR021
U 1 1 5C706766
P 7750 2750
F 0 "#PWR021" H 7750 2600 50  0001 C CNN
F 1 "+12V" H 7765 2923 50  0000 C CNN
F 2 "" H 7750 2750 50  0001 C CNN
F 3 "" H 7750 2750 50  0001 C CNN
	1    7750 2750
	-1   0    0    1   
$EndComp
$Comp
L power:+12V #PWR022
U 1 1 5C70678D
P 8050 2750
F 0 "#PWR022" H 8050 2600 50  0001 C CNN
F 1 "+12V" H 8065 2923 50  0000 C CNN
F 2 "" H 8050 2750 50  0001 C CNN
F 3 "" H 8050 2750 50  0001 C CNN
	1    8050 2750
	-1   0    0    1   
$EndComp
$Comp
L Connector:TestPoint W8
U 1 1 5C706806
P 8050 2600
F 0 "W8" H 8108 2720 50  0000 L CNN
F 1 "Cable hole" V 7950 2450 50  0000 L CNN
F 2 "discovery:fixing_hole" H 8250 2600 50  0001 C CNN
F 3 "~" H 8250 2600 50  0001 C CNN
	1    8050 2600
	1    0    0    -1  
$EndComp
$Comp
L Connector:TestPoint W9
U 1 1 5C70680C
P 8350 2600
F 0 "W9" H 8408 2720 50  0000 L CNN
F 1 "Cable hole" V 8250 2450 50  0000 L CNN
F 2 "discovery:fixing_hole" H 8550 2600 50  0001 C CNN
F 3 "~" H 8550 2600 50  0001 C CNN
	1    8350 2600
	1    0    0    -1  
$EndComp
$Comp
L Connector:TestPoint W10
U 1 1 5C706812
P 8650 2600
F 0 "W10" H 8708 2720 50  0000 L CNN
F 1 "Cable hole" V 8550 2450 50  0000 L CNN
F 2 "discovery:fixing_hole" H 8850 2600 50  0001 C CNN
F 3 "~" H 8850 2600 50  0001 C CNN
	1    8650 2600
	1    0    0    -1  
$EndComp
$Comp
L Connector:TestPoint W11
U 1 1 5C706818
P 8950 2600
F 0 "W11" H 9008 2720 50  0000 L CNN
F 1 "Cable hole" V 8850 2450 50  0000 L CNN
F 2 "discovery:fixing_hole" H 9150 2600 50  0001 C CNN
F 3 "~" H 9150 2600 50  0001 C CNN
	1    8950 2600
	1    0    0    -1  
$EndComp
$Comp
L power:GND #PWR023
U 1 1 5C708E3D
P 8350 2750
F 0 "#PWR023" H 8350 2500 50  0001 C CNN
F 1 "GND" H 8355 2577 50  0000 C CNN
F 2 "" H 8350 2750 50  0001 C CNN
F 3 "" H 8350 2750 50  0001 C CNN
	1    8350 2750
	1    0    0    -1  
$EndComp
$Comp
L power:GND #PWR024
U 1 1 5C708E7E
P 8650 2750
F 0 "#PWR024" H 8650 2500 50  0001 C CNN
F 1 "GND" H 8655 2577 50  0000 C CNN
F 2 "" H 8650 2750 50  0001 C CNN
F 3 "" H 8650 2750 50  0001 C CNN
	1    8650 2750
	1    0    0    -1  
$EndComp
$Comp
L power:GND #PWR025
U 1 1 5C708EAD
P 8950 2750
F 0 "#PWR025" H 8950 2500 50  0001 C CNN
F 1 "GND" H 8955 2577 50  0000 C CNN
F 2 "" H 8950 2750 50  0001 C CNN
F 3 "" H 8950 2750 50  0001 C CNN
	1    8950 2750
	1    0    0    -1  
$EndComp
$Comp
L power:GND #PWR026
U 1 1 5C708F7A
P 9250 2750
F 0 "#PWR026" H 9250 2500 50  0001 C CNN
F 1 "GND" H 9255 2577 50  0000 C CNN
F 2 "" H 9250 2750 50  0001 C CNN
F 3 "" H 9250 2750 50  0001 C CNN
	1    9250 2750
	1    0    0    -1  
$EndComp
Wire Wire Line
	7150 2600 7150 2750
Wire Wire Line
	7450 2600 7450 2750
Wire Wire Line
	7750 2600 7750 2750
Wire Wire Line
	8050 2600 8050 2750
Wire Wire Line
	8350 2600 8350 2750
Wire Wire Line
	8650 2600 8650 2750
Wire Wire Line
	8950 2600 8950 2750
Wire Wire Line
	9250 2600 9250 2750
Wire Wire Line
	3350 2150 3350 2050
Connection ~ 3350 2150
Wire Wire Line
	2650 2450 2650 2550
Connection ~ 2650 2450
Wire Wire Line
	1600 2550 1600 2450
Connection ~ 1600 2450
Wire Wire Line
	2300 2150 2300 2050
Connection ~ 2300 2150
$Comp
L Connector_Generic:Conn_02x03_Counter_Clockwise J2
U 1 1 5CAE0E4E
P 1900 3300
F 0 "J2" H 1950 3500 50  0000 C CNN
F 1 "Conn_02x03_PCIe" H 1900 3100 50  0000 C CNN
F 2 "discovery:CONN_02x03_4.2mm" H 1900 3300 50  0001 C CNN
F 3 "~" H 1900 3300 50  0001 C CNN
	1    1900 3300
	1    0    0    -1  
$EndComp
Wire Wire Line
	1700 3400 1600 3400
Wire Wire Line
	1600 3400 1600 3300
Wire Wire Line
	1700 3200 1600 3200
Connection ~ 1600 3200
Wire Wire Line
	1600 3200 1600 3100
Wire Wire Line
	1700 3300 1600 3300
Connection ~ 1600 3300
Wire Wire Line
	1600 3300 1600 3200
$Comp
L power:+12V #PWR0101
U 1 1 5CAE0FE2
P 1600 3100
F 0 "#PWR0101" H 1600 2950 50  0001 C CNN
F 1 "+12V" H 1615 3273 50  0000 C CNN
F 2 "" H 1600 3100 50  0001 C CNN
F 3 "" H 1600 3100 50  0001 C CNN
	1    1600 3100
	1    0    0    -1  
$EndComp
$Comp
L power:GND #PWR0102
U 1 1 5CAE466F
P 2300 3500
F 0 "#PWR0102" H 2300 3250 50  0001 C CNN
F 1 "GND" H 2305 3327 50  0000 C CNN
F 2 "" H 2300 3500 50  0001 C CNN
F 3 "" H 2300 3500 50  0001 C CNN
	1    2300 3500
	1    0    0    -1  
$EndComp
Wire Wire Line
	2200 3200 2300 3200
Wire Wire Line
	2300 3200 2300 3300
Wire Wire Line
	2200 3300 2300 3300
Connection ~ 2300 3300
Wire Wire Line
	2300 3300 2300 3400
Wire Wire Line
	2200 3400 2300 3400
Connection ~ 2300 3400
Wire Wire Line
	2300 3400 2300 3500
$Comp
L Connector_Generic:Conn_02x03_Counter_Clockwise J4
U 1 1 5CAEF7E4
P 2800 3300
F 0 "J4" H 2850 3500 50  0000 C CNN
F 1 "Conn_02x03_PCIe" H 2800 3100 50  0000 C CNN
F 2 "discovery:CONN_02x03_4.2mm" H 2800 3300 50  0001 C CNN
F 3 "~" H 2800 3300 50  0001 C CNN
	1    2800 3300
	1    0    0    -1  
$EndComp
Wire Wire Line
	2600 3400 2500 3400
Wire Wire Line
	2500 3400 2500 3300
Wire Wire Line
	2600 3200 2500 3200
Connection ~ 2500 3200
Wire Wire Line
	2500 3200 2500 3100
Wire Wire Line
	2600 3300 2500 3300
Connection ~ 2500 3300
Wire Wire Line
	2500 3300 2500 3200
$Comp
L power:+12V #PWR0103
U 1 1 5CAEF7F2
P 2500 3100
F 0 "#PWR0103" H 2500 2950 50  0001 C CNN
F 1 "+12V" H 2515 3273 50  0000 C CNN
F 2 "" H 2500 3100 50  0001 C CNN
F 3 "" H 2500 3100 50  0001 C CNN
	1    2500 3100
	1    0    0    -1  
$EndComp
$Comp
L power:GND #PWR0104
U 1 1 5CAEF7F8
P 3200 3500
F 0 "#PWR0104" H 3200 3250 50  0001 C CNN
F 1 "GND" H 3205 3327 50  0000 C CNN
F 2 "" H 3200 3500 50  0001 C CNN
F 3 "" H 3200 3500 50  0001 C CNN
	1    3200 3500
	1    0    0    -1  
$EndComp
Wire Wire Line
	3100 3200 3200 3200
Wire Wire Line
	3200 3200 3200 3300
Wire Wire Line
	3100 3300 3200 3300
Connection ~ 3200 3300
Wire Wire Line
	3200 3300 3200 3400
Wire Wire Line
	3100 3400 3200 3400
Connection ~ 3200 3400
Wire Wire Line
	3200 3400 3200 3500
$Comp
L Connector_Generic:Conn_02x03_Counter_Clockwise J5
U 1 1 5CAF9889
P 3700 3300
F 0 "J5" H 3750 3500 50  0000 C CNN
F 1 "Conn_02x03_PCIe" H 3700 3100 50  0000 C CNN
F 2 "discovery:CONN_02x03_4.2mm" H 3700 3300 50  0001 C CNN
F 3 "~" H 3700 3300 50  0001 C CNN
	1    3700 3300
	1    0    0    -1  
$EndComp
Wire Wire Line
	3500 3400 3400 3400
Wire Wire Line
	3400 3400 3400 3300
Wire Wire Line
	3500 3200 3400 3200
Connection ~ 3400 3200
Wire Wire Line
	3400 3200 3400 3100
Wire Wire Line
	3500 3300 3400 3300
Connection ~ 3400 3300
Wire Wire Line
	3400 3300 3400 3200
$Comp
L power:+12V #PWR0105
U 1 1 5CAF9897
P 3400 3100
F 0 "#PWR0105" H 3400 2950 50  0001 C CNN
F 1 "+12V" H 3415 3273 50  0000 C CNN
F 2 "" H 3400 3100 50  0001 C CNN
F 3 "" H 3400 3100 50  0001 C CNN
	1    3400 3100
	1    0    0    -1  
$EndComp
$Comp
L power:GND #PWR0106
U 1 1 5CAF989D
P 4100 3500
F 0 "#PWR0106" H 4100 3250 50  0001 C CNN
F 1 "GND" H 4105 3327 50  0000 C CNN
F 2 "" H 4100 3500 50  0001 C CNN
F 3 "" H 4100 3500 50  0001 C CNN
	1    4100 3500
	1    0    0    -1  
$EndComp
Wire Wire Line
	4000 3200 4100 3200
Wire Wire Line
	4100 3200 4100 3300
Wire Wire Line
	4000 3300 4100 3300
Connection ~ 4100 3300
Wire Wire Line
	4100 3300 4100 3400
Wire Wire Line
	4000 3400 4100 3400
Connection ~ 4100 3400
Wire Wire Line
	4100 3400 4100 3500
$Comp
L Connector_Generic:Conn_02x03_Counter_Clockwise J6
U 1 1 5CAF98AB
P 4600 3300
F 0 "J6" H 4650 3500 50  0000 C CNN
F 1 "Conn_02x03_PCIe" H 4600 3100 50  0000 C CNN
F 2 "discovery:CONN_02x03_4.2mm" H 4600 3300 50  0001 C CNN
F 3 "~" H 4600 3300 50  0001 C CNN
	1    4600 3300
	1    0    0    -1  
$EndComp
Wire Wire Line
	4400 3400 4300 3400
Wire Wire Line
	4300 3400 4300 3300
Wire Wire Line
	4400 3200 4300 3200
Connection ~ 4300 3200
Wire Wire Line
	4300 3200 4300 3100
Wire Wire Line
	4400 3300 4300 3300
Connection ~ 4300 3300
Wire Wire Line
	4300 3300 4300 3200
$Comp
L power:+12V #PWR0107
U 1 1 5CAF98B9
P 4300 3100
F 0 "#PWR0107" H 4300 2950 50  0001 C CNN
F 1 "+12V" H 4315 3273 50  0000 C CNN
F 2 "" H 4300 3100 50  0001 C CNN
F 3 "" H 4300 3100 50  0001 C CNN
	1    4300 3100
	1    0    0    -1  
$EndComp
$Comp
L power:GND #PWR0108
U 1 1 5CAF98BF
P 5000 3500
F 0 "#PWR0108" H 5000 3250 50  0001 C CNN
F 1 "GND" H 5005 3327 50  0000 C CNN
F 2 "" H 5000 3500 50  0001 C CNN
F 3 "" H 5000 3500 50  0001 C CNN
	1    5000 3500
	1    0    0    -1  
$EndComp
Wire Wire Line
	4900 3200 5000 3200
Wire Wire Line
	5000 3200 5000 3300
Wire Wire Line
	4900 3300 5000 3300
Connection ~ 5000 3300
Wire Wire Line
	5000 3300 5000 3400
Wire Wire Line
	4900 3400 5000 3400
Connection ~ 5000 3400
Wire Wire Line
	5000 3400 5000 3500
$EndSCHEMATC
